(kicad_pcb
	(version 20260206)
	(generator "pcbnew")
	(generator_version "10.0")
	(general
		(thickness 1.6)
		(legacy_teardrops no)
	)
	(paper "A4")
	(title_block
		(title "Bryce Canyon_IOM_M2_16342-2_OCP.brd")
		(comment 1 "Bryce Canyon / footprints 1114-1122 of 1146")
	)
	(layers
		(0 "F.Cu" signal "TOP")
		(4 "In1.Cu" signal "L2GND")
		(6 "In2.Cu" signal "L3")
		(8 "In3.Cu" signal "L4VCC")
		(10 "In4.Cu" signal "L5VCC")
		(12 "In5.Cu" signal "L6")
		(14 "In6.Cu" signal "L7GND")
		(2 "B.Cu" signal "BOTTOM")
		(9 "F.Adhes" user "F.Adhesive")
		(11 "B.Adhes" user "B.Adhesive")
		(13 "F.Paste" user "Package Geometry/Pastemask Top")
		(15 "B.Paste" user "Package Geometry/Pastemask Bottom")
		(5 "F.SilkS" user "Ref Des/Silkscreen Top")
		(7 "B.SilkS" user "Ref Des/Silkscreen Bottom")
		(1 "F.Mask" user "Board Geometry/Soldermask Top")
		(3 "B.Mask" user "Board Geometry/Soldermask Bottom")
		(17 "Dwgs.User" user "User.Drawings")
		(19 "Cmts.User" user "User.Comments")
		(21 "Eco1.User" user "User.Eco1")
		(23 "Eco2.User" user "User.Eco2")
		(25 "Edge.Cuts" user "Board Geometry/Outline")
		(27 "Margin" user)
		(31 "F.CrtYd" user "Package Geometry/Place Bound Top")
		(29 "B.CrtYd" user "Package Geometry/Place Bound Bottom")
		(35 "F.Fab" user "Ref Des/Assembly Top")
		(33 "B.Fab" user "Ref Des/Assembly Bottom")
	)
	(footprint ""
		(layer "B.Cu")
		(at 25.343104 -142.282164 -90)
		(property "Reference" "R222"
			(at 0 0 90)
			(layer "B.SilkS")
			(hide yes)
			(effects
				(font
					(size 1.27 1.27)
				)
				(justify mirror)
			)
		)
		(property "Value" "120R2F-GP"
			(at -0.064008 -3.993896 270)
			(unlocked yes)
			(layer "B.Fab")
			(hide yes)
			(effects
				(font
					(size 1.016 1.016)
					(thickness 0.1524)
				)
				(justify mirror)
			)
		)
		(property "Device Type" "R402H16"
			(at -0.064008 -5.517896 270)
			(unlocked yes)
			(layer "B.Fab")
			(hide yes)
			(effects
				(font
					(size 1.016 1.016)
					(thickness 0.1524)
				)
				(justify mirror)
			)
		)
		(duplicate_pad_numbers_are_jumpers no)
		(fp_line
			(start -0.508 -0.9398)
			(end 0.508 -0.9398)
			(stroke
				(width 0.1524)
				(type default)
			)
			(layer "B.SilkS")
		)
		(fp_line
			(start 0.508 -0.9398)
			(end 0.508 0.9398)
			(stroke
				(width 0.1524)
				(type default)
			)
			(layer "B.SilkS")
		)
		(fp_rect
			(start 0.508 0.9398)
			(end -0.508 -0.9398)
			(stroke
				(width 0)
				(type default)
			)
			(fill no)
			(layer "B.CrtYd")
		)
		(fp_rect
			(start 0.508 0.9398)
			(end -0.508 -0.9398)
			(stroke
				(width 0)
				(type default)
			)
			(fill no)
			(layer "B.Fab")
		)
		(pad "1" smd custom
			(at 0 -0.4445 90)
			(size 0.1397 0.1397)
			(layers "B.Cu" "B.Mask" "B.Paste")
			(net "GND")
			(options
				(clearance outline)
				(anchor circle)
			)
			(primitives
				(gr_poly
					(pts
						(arc
							(start -0.1778 0.2794)
							(mid -0.249642 0.249642)
							(end -0.2794 0.1778)
						)
						(arc
							(start -0.2794 -0.1778)
							(mid -0.249642 -0.249642)
							(end -0.1778 -0.2794)
						)
						(arc
							(start 0.1778 -0.2794)
							(mid 0.249642 -0.249642)
							(end 0.2794 -0.1778)
						)
						(arc
							(start 0.2794 0.1778)
							(mid 0.249642 0.249642)
							(end 0.1778 0.2794)
						)
					)
					(width 0)
					(fill yes)
				)
			)
		)
		(pad "2" smd custom
			(at 0 0.4445 90)
			(size 0.1397 0.1397)
			(layers "B.Cu" "B.Mask" "B.Paste")
			(net "MEMRASN")
			(options
				(clearance outline)
				(anchor circle)
			)
			(primitives
				(gr_poly
					(pts
						(arc
							(start -0.1778 0.2794)
							(mid -0.249642 0.249642)
							(end -0.2794 0.1778)
						)
						(arc
							(start -0.2794 -0.1778)
							(mid -0.249642 -0.249642)
							(end -0.1778 -0.2794)
						)
						(arc
							(start 0.1778 -0.2794)
							(mid 0.249642 -0.249642)
							(end 0.2794 -0.1778)
						)
						(arc
							(start 0.2794 0.1778)
							(mid 0.249642 0.249642)
							(end 0.1778 0.2794)
						)
					)
					(width 0)
					(fill yes)
				)
			)
		)
	)
	(footprint ""
		(layer "B.Cu")
		(at 46.9392 -123.077224)
		(property "Reference" "TP203"
			(at 0 0 0)
			(layer "B.SilkS")
			(hide yes)
			(effects
				(font
					(size 1.27 1.27)
				)
				(justify mirror)
			)
		)
		(property "Value" "TPAD28-2-GP"
			(at 0.0127 -1.6637 0)
			(unlocked yes)
			(layer "B.Fab")
			(hide yes)
			(effects
				(font
					(size 1.016 1.016)
					(thickness 0.1524)
				)
				(justify mirror)
			)
		)
		(property "Device Type" "TPAD28"
			(at 0.0127 -3.1877 0)
			(unlocked yes)
			(layer "B.Fab")
			(hide yes)
			(effects
				(font
					(size 1.016 1.016)
					(thickness 0.1524)
				)
				(justify mirror)
			)
		)
		(duplicate_pad_numbers_are_jumpers no)
		(fp_poly
			(pts
				(arc
					(start 0.3556 0)
					(mid -0.3556 0)
					(end 0.3556 0)
				)
			)
			(stroke
				(width 0)
				(type default)
			)
			(fill no)
			(layer "B.CrtYd")
		)
		(fp_poly
			(pts
				(arc
					(start 0.6096 0)
					(mid -0.6096 0)
					(end 0.6096 0)
				)
			)
			(stroke
				(width 0)
				(type default)
			)
			(fill no)
			(layer "B.Fab")
		)
		(pad "1" smd circle
			(at 0 0 180)
			(size 0.7112 0.7112)
			(layers "B.Cu" "B.Mask" "B.Paste")
			(net "BMC_SMB2_CLK_TP")
		)
	)
	(footprint ""
		(layer "B.Cu")
		(at 219.325444 -40.51046 90)
		(property "Reference" "C158"
			(at 0 0 90)
			(layer "B.SilkS")
			(hide yes)
			(effects
				(font
					(size 1.27 1.27)
				)
				(justify mirror)
			)
		)
		(property "Value" "SCD1U50V3KX-GP"
			(at 0 -2.8194 90)
			(unlocked yes)
			(layer "B.Fab")
			(hide yes)
			(effects
				(font
					(size 1.016 1.016)
					(thickness 0.1524)
				)
				(justify mirror)
			)
		)
		(property "Device Type" "C603H36"
			(at 0 -4.3434 90)
			(unlocked yes)
			(layer "B.Fab")
			(hide yes)
			(effects
				(font
					(size 1.016 1.016)
					(thickness 0.1524)
				)
				(justify mirror)
			)
		)
		(duplicate_pad_numbers_are_jumpers no)
		(fp_line
			(start -0.508 0)
			(end 0.508 0)
			(stroke
				(width 0.2032)
				(type default)
			)
			(layer "B.SilkS")
		)
		(fp_rect
			(start 0.5842 1.3335)
			(end -0.5842 -1.3335)
			(stroke
				(width 0)
				(type default)
			)
			(fill no)
			(layer "B.CrtYd")
		)
		(fp_rect
			(start 0.5842 1.3335)
			(end -0.5842 -1.3335)
			(stroke
				(width 0)
				(type default)
			)
			(fill no)
			(layer "B.Fab")
		)
		(pad "1" smd custom
			(at 0 -0.762 270)
			(size 0.2159 0.2159)
			(layers "B.Cu" "B.Mask" "B.Paste")
			(net "P5V_VBST_RC")
			(options
				(clearance outline)
				(anchor circle)
			)
			(primitives
				(gr_poly
					(pts
						(arc
							(start -0.3302 0.4318)
							(mid -0.402042 0.402042)
							(end -0.4318 0.3302)
						)
						(arc
							(start -0.4318 -0.3302)
							(mid -0.402042 -0.402042)
							(end -0.3302 -0.4318)
						)
						(arc
							(start 0.3302 -0.4318)
							(mid 0.402042 -0.402042)
							(end 0.4318 -0.3302)
						)
						(arc
							(start 0.4318 0.3302)
							(mid 0.402042 0.402042)
							(end 0.3302 0.4318)
						)
					)
					(width 0)
					(fill yes)
				)
			)
		)
		(pad "2" smd custom
			(at 0 0.762 270)
			(size 0.2159 0.2159)
			(layers "B.Cu" "B.Mask" "B.Paste")
			(net "P5V_LL")
			(options
				(clearance outline)
				(anchor circle)
			)
			(primitives
				(gr_poly
					(pts
						(arc
							(start -0.3302 0.4318)
							(mid -0.402042 0.402042)
							(end -0.4318 0.3302)
						)
						(arc
							(start -0.4318 -0.3302)
							(mid -0.402042 -0.402042)
							(end -0.3302 -0.4318)
						)
						(arc
							(start 0.3302 -0.4318)
							(mid 0.402042 -0.402042)
							(end 0.4318 -0.3302)
						)
						(arc
							(start 0.4318 0.3302)
							(mid 0.402042 0.402042)
							(end 0.3302 0.4318)
						)
					)
					(width 0)
					(fill yes)
				)
			)
		)
	)
	(footprint ""
		(layer "B.Cu")
		(at 96.25711 -155.095702 45)
		(property "Reference" "TP6"
			(at 0 0 45)
			(layer "B.SilkS")
			(hide yes)
			(effects
				(font
					(size 1.27 1.27)
				)
				(justify mirror)
			)
		)
		(property "Value" "TPAD28-2-GP"
			(at 0.012752 -1.663607 45)
			(unlocked yes)
			(layer "B.Fab")
			(hide yes)
			(effects
				(font
					(size 1.016 1.016)
					(thickness 0.1524)
				)
				(justify mirror)
			)
		)
		(property "Device Type" "TPAD28"
			(at 0.012752 -3.187736 45)
			(unlocked yes)
			(layer "B.Fab")
			(hide yes)
			(effects
				(font
					(size 1.016 1.016)
					(thickness 0.1524)
				)
				(justify mirror)
			)
		)
		(duplicate_pad_numbers_are_jumpers no)
		(fp_poly
			(pts
				(arc
					(start 0.251447 0.251447)
					(mid -0.251447 -0.251447)
					(end 0.251447 0.251447)
				)
			)
			(stroke
				(width 0)
				(type default)
			)
			(fill no)
			(layer "B.CrtYd")
		)
		(fp_poly
			(pts
				(arc
					(start 0.431052 0.431052)
					(mid -0.431052 -0.431052)
					(end 0.431052 0.431052)
				)
			)
			(stroke
				(width 0)
				(type default)
			)
			(fill no)
			(layer "B.Fab")
		)
		(pad "1" smd circle
			(at 0 0 225)
			(size 0.7112 0.7112)
			(layers "B.Cu" "B.Mask" "B.Paste")
			(net "TP_USB_SDA")
		)
	)
	(footprint ""
		(layer "B.Cu")
		(at 29.075888 -126.31547 90)
		(property "Reference" "R783"
			(at 0 0 90)
			(layer "B.SilkS")
			(hide yes)
			(effects
				(font
					(size 1.27 1.27)
				)
				(justify mirror)
			)
		)
		(property "Value" "10KR2F-2-GP"
			(at -0.064008 -3.993896 90)
			(unlocked yes)
			(layer "B.Fab")
			(hide yes)
			(effects
				(font
					(size 1.016 1.016)
					(thickness 0.1524)
				)
				(justify mirror)
			)
		)
		(property "Device Type" "R402H16"
			(at -0.064008 -5.517896 90)
			(unlocked yes)
			(layer "B.Fab")
			(hide yes)
			(effects
				(font
					(size 1.016 1.016)
					(thickness 0.1524)
				)
				(justify mirror)
			)
		)
		(duplicate_pad_numbers_are_jumpers no)
		(fp_line
			(start 0.508 -0.9398)
			(end 0.508 0.9398)
			(stroke
				(width 0.1524)
				(type default)
			)
			(layer "B.SilkS")
		)
		(fp_line
			(start -0.508 -0.9398)
			(end 0.508 -0.9398)
			(stroke
				(width 0.1524)
				(type default)
			)
			(layer "B.SilkS")
		)
		(fp_rect
			(start 0.508 0.9398)
			(end -0.508 -0.9398)
			(stroke
				(width 0)
				(type default)
			)
			(fill no)
			(layer "B.CrtYd")
		)
		(fp_rect
			(start 0.508 0.9398)
			(end -0.508 -0.9398)
			(stroke
				(width 0)
				(type default)
			)
			(fill no)
			(layer "B.Fab")
		)
		(pad "1" smd custom
			(at 0 -0.4445 270)
			(size 0.1397 0.1397)
			(layers "B.Cu" "B.Mask" "B.Paste")
			(net "P3V3_STBY")
			(options
				(clearance outline)
				(anchor circle)
			)
			(primitives
				(gr_poly
					(pts
						(arc
							(start -0.1778 0.2794)
							(mid -0.249642 0.249642)
							(end -0.2794 0.1778)
						)
						(arc
							(start -0.2794 -0.1778)
							(mid -0.249642 -0.249642)
							(end -0.1778 -0.2794)
						)
						(arc
							(start 0.1778 -0.2794)
							(mid 0.249642 -0.249642)
							(end 0.2794 -0.1778)
						)
						(arc
							(start 0.2794 0.1778)
							(mid 0.249642 0.249642)
							(end 0.1778 0.2794)
						)
					)
					(width 0)
					(fill yes)
				)
			)
		)
		(pad "2" smd custom
			(at 0 0.4445 270)
			(size 0.1397 0.1397)
			(layers "B.Cu" "B.Mask" "B.Paste")
			(net "SYS_RESET_N_OUT")
			(options
				(clearance outline)
				(anchor circle)
			)
			(primitives
				(gr_poly
					(pts
						(arc
							(start -0.1778 0.2794)
							(mid -0.249642 0.249642)
							(end -0.2794 0.1778)
						)
						(arc
							(start -0.2794 -0.1778)
							(mid -0.249642 -0.249642)
							(end -0.1778 -0.2794)
						)
						(arc
							(start 0.1778 -0.2794)
							(mid 0.249642 -0.249642)
							(end 0.2794 -0.1778)
						)
						(arc
							(start 0.2794 0.1778)
							(mid 0.249642 0.249642)
							(end 0.1778 0.2794)
						)
					)
					(width 0)
					(fill yes)
				)
			)
		)
	)
	(footprint ""
		(layer "B.Cu")
		(at 10.1854 -142.4686 90)
		(property "Reference" "R211"
			(at 0 0 90)
			(layer "B.SilkS")
			(hide yes)
			(effects
				(font
					(size 1.27 1.27)
				)
				(justify mirror)
			)
		)
		(property "Value" "120R2F-GP"
			(at -0.064008 -3.993896 90)
			(unlocked yes)
			(layer "B.Fab")
			(hide yes)
			(effects
				(font
					(size 1.016 1.016)
					(thickness 0.1524)
				)
				(justify mirror)
			)
		)
		(property "Device Type" "R402H16"
			(at -0.064008 -5.517896 90)
			(unlocked yes)
			(layer "B.Fab")
			(hide yes)
			(effects
				(font
					(size 1.016 1.016)
					(thickness 0.1524)
				)
				(justify mirror)
			)
		)
		(duplicate_pad_numbers_are_jumpers no)
		(fp_line
			(start 0.508 -0.9398)
			(end 0.508 0.9398)
			(stroke
				(width 0.1524)
				(type default)
			)
			(layer "B.SilkS")
		)
		(fp_line
			(start -0.508 -0.9398)
			(end 0.508 -0.9398)
			(stroke
				(width 0.1524)
				(type default)
			)
			(layer "B.SilkS")
		)
		(fp_rect
			(start 0.508 0.9398)
			(end -0.508 -0.9398)
			(stroke
				(width 0)
				(type default)
			)
			(fill no)
			(layer "B.CrtYd")
		)
		(fp_rect
			(start 0.508 0.9398)
			(end -0.508 -0.9398)
			(stroke
				(width 0)
				(type default)
			)
			(fill no)
			(layer "B.Fab")
		)
		(pad "1" smd custom
			(at 0 -0.4445 270)
			(size 0.1397 0.1397)
			(layers "B.Cu" "B.Mask" "B.Paste")
			(net "GND")
			(options
				(clearance outline)
				(anchor circle)
			)
			(primitives
				(gr_poly
					(pts
						(arc
							(start -0.1778 0.2794)
							(mid -0.249642 0.249642)
							(end -0.2794 0.1778)
						)
						(arc
							(start -0.2794 -0.1778)
							(mid -0.249642 -0.249642)
							(end -0.1778 -0.2794)
						)
						(arc
							(start 0.1778 -0.2794)
							(mid 0.249642 -0.249642)
							(end 0.2794 -0.1778)
						)
						(arc
							(start 0.2794 0.1778)
							(mid 0.249642 0.249642)
							(end 0.1778 0.2794)
						)
					)
					(width 0)
					(fill yes)
				)
			)
		)
		(pad "2" smd custom
			(at 0 0.4445 270)
			(size 0.1397 0.1397)
			(layers "B.Cu" "B.Mask" "B.Paste")
			(net "MEMODT")
			(options
				(clearance outline)
				(anchor circle)
			)
			(primitives
				(gr_poly
					(pts
						(arc
							(start -0.1778 0.2794)
							(mid -0.249642 0.249642)
							(end -0.2794 0.1778)
						)
						(arc
							(start -0.2794 -0.1778)
							(mid -0.249642 -0.249642)
							(end -0.1778 -0.2794)
						)
						(arc
							(start 0.1778 -0.2794)
							(mid 0.249642 -0.249642)
							(end 0.2794 -0.1778)
						)
						(arc
							(start 0.2794 0.1778)
							(mid 0.249642 0.249642)
							(end 0.1778 0.2794)
						)
					)
					(width 0)
					(fill yes)
				)
			)
		)
	)
	(footprint ""
		(layer "B.Cu")
		(at 82.5754 -59.7916 -90)
		(property "Reference" "C29"
			(at 0 0 90)
			(layer "B.SilkS")
			(hide yes)
			(effects
				(font
					(size 1.27 1.27)
				)
				(justify mirror)
			)
		)
		(property "Value" "SC2D2U25V5KX-2-GP"
			(at 0.0762 -6.1214 270)
			(unlocked yes)
			(layer "B.Fab")
			(hide yes)
			(effects
				(font
					(size 1.016 1.016)
					(thickness 0.1524)
				)
				(justify mirror)
			)
		)
		(property "Device Type" "C805H54"
			(at 0.0762 -8.1534 270)
			(unlocked yes)
			(layer "B.Fab")
			(hide yes)
			(effects
				(font
					(size 1.016 1.016)
					(thickness 0.1524)
				)
				(justify mirror)
			)
		)
		(duplicate_pad_numbers_are_jumpers no)
		(fp_line
			(start -0.635 0)
			(end 0.635 0)
			(stroke
				(width 0.508)
				(type default)
			)
			(layer "B.SilkS")
		)
		(fp_rect
			(start 0.9652 1.778)
			(end -0.9652 -1.778)
			(stroke
				(width 0)
				(type default)
			)
			(fill no)
			(layer "B.CrtYd")
		)
		(fp_poly
			(pts
				(xy 0.9652 -1.778) (xy -0.9652 -1.778) (xy -0.9652 1.778) (xy 0.9652 1.778)
			)
			(stroke
				(width 0)
				(type default)
			)
			(fill no)
			(layer "B.Fab")
		)
		(pad "1" smd rect
			(at 0 -0.9652 90)
			(size 1.397 1.143)
			(layers "B.Cu" "B.Mask" "B.Paste")
			(net "P3V3_STBY")
		)
		(pad "2" smd rect
			(at 0 0.9652 90)
			(size 1.397 1.143)
			(layers "B.Cu" "B.Mask" "B.Paste")
			(net "GND")
		)
	)
	(footprint ""
		(layer "B.Cu")
		(at 121.245122 -9.504426 180)
		(property "Reference" "CA1"
			(at 0 0 0)
			(layer "B.SilkS")
			(hide yes)
			(effects
				(font
					(size 1.27 1.27)
				)
				(justify mirror)
			)
		)
		(property "Value" "SC2D2U25V5KX-2-GP"
			(at 0.0762 -6.1214 180)
			(unlocked yes)
			(layer "B.Fab")
			(hide yes)
			(effects
				(font
					(size 1.016 1.016)
					(thickness 0.1524)
				)
				(justify mirror)
			)
		)
		(property "Device Type" "C805H54"
			(at 0.0762 -8.1534 180)
			(unlocked yes)
			(layer "B.Fab")
			(hide yes)
			(effects
				(font
					(size 1.016 1.016)
					(thickness 0.1524)
				)
				(justify mirror)
			)
		)
		(duplicate_pad_numbers_are_jumpers no)
		(fp_line
			(start -0.635 0)
			(end 0.635 0)
			(stroke
				(width 0.508)
				(type default)
			)
			(layer "B.SilkS")
		)
		(fp_rect
			(start 0.9652 1.778)
			(end -0.9652 -1.778)
			(stroke
				(width 0)
				(type default)
			)
			(fill no)
			(layer "B.CrtYd")
		)
		(fp_poly
			(pts
				(xy 0.9652 -1.778) (xy -0.9652 -1.778) (xy -0.9652 1.778) (xy 0.9652 1.778)
			)
			(stroke
				(width 0)
				(type default)
			)
			(fill no)
			(layer "B.Fab")
		)
		(pad "1" smd rect
			(at 0 -0.9652)
			(size 1.397 1.143)
			(layers "B.Cu" "B.Mask" "B.Paste")
			(net "P12V_IOM_PGOOD")
		)
		(pad "2" smd rect
			(at 0 0.9652)
			(size 1.397 1.143)
			(layers "B.Cu" "B.Mask" "B.Paste")
			(net "GND")
		)
	)
	(footprint ""
		(layer "B.Cu")
		(at 48.913034 -142.03934 -90)
		(property "Reference" "C100"
			(at 0 0 90)
			(layer "B.SilkS")
			(hide yes)
			(effects
				(font
					(size 1.27 1.27)
				)
				(justify mirror)
			)
		)
		(property "Value" "SC1U16V3KX-5GP"
			(at 0 -2.8194 270)
			(unlocked yes)
			(layer "B.Fab")
			(hide yes)
			(effects
				(font
					(size 1.016 1.016)
					(thickness 0.1524)
				)
				(justify mirror)
			)
		)
		(property "Device Type" "C603H36"
			(at 0 -4.3434 270)
			(unlocked yes)
			(layer "B.Fab")
			(hide yes)
			(effects
				(font
					(size 1.016 1.016)
					(thickness 0.1524)
				)
				(justify mirror)
			)
		)
		(duplicate_pad_numbers_are_jumpers no)
		(fp_line
			(start -0.508 0)
			(end 0.508 0)
			(stroke
				(width 0.2032)
				(type default)
			)
			(layer "B.SilkS")
		)
		(fp_rect
			(start 0.5842 1.3335)
			(end -0.5842 -1.3335)
			(stroke
				(width 0)
				(type default)
			)
			(fill no)
			(layer "B.CrtYd")
		)
		(fp_rect
			(start 0.5842 1.3335)
			(end -0.5842 -1.3335)
			(stroke
				(width 0)
				(type default)
			)
			(fill no)
			(layer "B.Fab")
		)
		(pad "1" smd custom
			(at 0 -0.762 90)
			(size 0.2159 0.2159)
			(layers "B.Cu" "B.Mask" "B.Paste")
			(net "P3V3_STBY")
			(options
				(clearance outline)
				(anchor circle)
			)
			(primitives
				(gr_poly
					(pts
						(arc
							(start -0.3302 0.4318)
							(mid -0.402042 0.402042)
							(end -0.4318 0.3302)
						)
						(arc
							(start -0.4318 -0.3302)
							(mid -0.402042 -0.402042)
							(end -0.3302 -0.4318)
						)
						(arc
							(start 0.3302 -0.4318)
							(mid 0.402042 -0.402042)
							(end 0.4318 -0.3302)
						)
						(arc
							(start 0.4318 0.3302)
							(mid 0.402042 0.402042)
							(end 0.3302 0.4318)
						)
					)
					(width 0)
					(fill yes)
				)
			)
		)
		(pad "2" smd custom
			(at 0 0.762 90)
			(size 0.2159 0.2159)
			(layers "B.Cu" "B.Mask" "B.Paste")
			(net "GND")
			(options
				(clearance outline)
				(anchor circle)
			)
			(primitives
				(gr_poly
					(pts
						(arc
							(start -0.3302 0.4318)
							(mid -0.402042 0.402042)
							(end -0.4318 0.3302)
						)
						(arc
							(start -0.4318 -0.3302)
							(mid -0.402042 -0.402042)
							(end -0.3302 -0.4318)
						)
						(arc
							(start 0.3302 -0.4318)
							(mid 0.402042 -0.402042)
							(end 0.4318 -0.3302)
						)
						(arc
							(start 0.4318 0.3302)
							(mid 0.402042 0.402042)
							(end 0.3302 0.4318)
						)
					)
					(width 0)
					(fill yes)
				)
			)
		)
	)
)
